(kicad_pcb
	(version 20260206)
	(generator "pcbnew")
	(generator_version "10.0")
	(general
		(thickness 1.6)
		(legacy_teardrops no)
	)
	(paper "A4")
	(title_block
		(title "04192023_DAF0TMB3IC0_F0TG_MB_C_brd_V02_OCP.brd")
		(comment 1 "Grand Teton / footprints 940-946 of 8354")
	)
	(layers
		(0 "F.Cu" signal "TOP")
		(4 "In1.Cu" signal "GND")
		(6 "In2.Cu" signal "IN1")
		(8 "In3.Cu" signal "GND1")
		(10 "In4.Cu" signal "IN2")
		(12 "In5.Cu" signal "GND2")
		(14 "In6.Cu" signal "IN3")
		(16 "In7.Cu" signal "GND3")
		(18 "In8.Cu" signal "VCC")
		(20 "In9.Cu" signal "VCC1")
		(22 "In10.Cu" signal "GND4")
		(24 "In11.Cu" signal "IN4")
		(26 "In12.Cu" signal "GND5")
		(28 "In13.Cu" signal "IN5")
		(30 "In14.Cu" signal "GND6")
		(32 "In15.Cu" signal "IN6")
		(34 "In16.Cu" signal "GND7")
		(2 "B.Cu" signal "BOTTOM")
		(9 "F.Adhes" user "F.Adhesive")
		(11 "B.Adhes" user "B.Adhesive")
		(13 "F.Paste" user "Package Geometry/Pastemask Top")
		(15 "B.Paste" user "Package Geometry/Pastemask Bottom")
		(5 "F.SilkS" user "Ref Des/Silkscreen Top")
		(7 "B.SilkS" user "Ref Des/Silkscreen Bottom")
		(1 "F.Mask" user "Board Geometry/Soldermask Top")
		(3 "B.Mask" user "Board Geometry/Soldermask Bottom")
		(17 "Dwgs.User" user "User.Drawings")
		(19 "Cmts.User" user "User.Comments")
		(21 "Eco1.User" user "User.Eco1")
		(23 "Eco2.User" user "User.Eco2")
		(25 "Edge.Cuts" user "Board Geometry/Outline")
		(27 "Margin" user)
		(31 "F.CrtYd" user "Package Geometry/Place Bound Top")
		(29 "B.CrtYd" user "Package Geometry/Place Bound Bottom")
		(35 "F.Fab" user "Ref Des/Assembly Top")
		(33 "B.Fab" user "Ref Des/Assembly Bottom")
	)
	(footprint ""
		(layer "F.Cu")
		(at 392.103102 -177.88636 -90)
		(property "Reference" "PC545_4"
			(at 0 0 270)
			(layer "F.SilkS")
			(hide yes)
			(effects
				(font
					(size 1.27 1.27)
				)
			)
		)
		(property "Value" ""
			(at 0 0 270)
			(layer "F.Fab")
			(effects
				(font
					(size 1.27 1.27)
				)
			)
		)
		(duplicate_pad_numbers_are_jumpers no)
		(fp_line
			(start -0.7874 0.4064)
			(end -0.7874 -0.4064)
			(stroke
				(width 0.1524)
				(type default)
			)
			(layer "F.SilkS")
		)
		(fp_line
			(start 0.7874 0.4064)
			(end -0.7874 0.4064)
			(stroke
				(width 0.1524)
				(type default)
			)
			(layer "F.SilkS")
		)
		(fp_line
			(start -0.7874 -0.4064)
			(end 0.7874 -0.4064)
			(stroke
				(width 0.1524)
				(type default)
			)
			(layer "F.SilkS")
		)
		(fp_line
			(start 0.7874 -0.4064)
			(end 0.7874 0.4064)
			(stroke
				(width 0.1524)
				(type default)
			)
			(layer "F.SilkS")
		)
		(fp_line
			(start -0.67945 0.3048)
			(end -0.67945 -0.305054)
			(stroke
				(width 0.1)
				(type default)
			)
			(layer "F.Fab")
		)
		(fp_line
			(start -0.12065 0.3048)
			(end -0.67945 0.3048)
			(stroke
				(width 0.1)
				(type default)
			)
			(layer "F.Fab")
		)
		(fp_line
			(start 0.120396 0.3048)
			(end 0.120396 0.2794)
			(stroke
				(width 0.1)
				(type default)
			)
			(layer "F.Fab")
		)
		(fp_line
			(start 0.67945 0.3048)
			(end 0.120396 0.3048)
			(stroke
				(width 0.1)
				(type default)
			)
			(layer "F.Fab")
		)
		(fp_line
			(start -0.12065 0.2794)
			(end -0.12065 0.3048)
			(stroke
				(width 0.1)
				(type default)
			)
			(layer "F.Fab")
		)
		(fp_line
			(start 0.120396 0.2794)
			(end -0.12065 0.2794)
			(stroke
				(width 0.1)
				(type default)
			)
			(layer "F.Fab")
		)
		(fp_line
			(start -0.12065 -0.2794)
			(end 0.12065 -0.2794)
			(stroke
				(width 0.1)
				(type default)
			)
			(layer "F.Fab")
		)
		(fp_line
			(start 0.12065 -0.2794)
			(end 0.12065 -0.3048)
			(stroke
				(width 0.1)
				(type default)
			)
			(layer "F.Fab")
		)
		(fp_line
			(start 0.12065 -0.3048)
			(end 0.67945 -0.3048)
			(stroke
				(width 0.1)
				(type default)
			)
			(layer "F.Fab")
		)
		(fp_line
			(start 0.67945 -0.3048)
			(end 0.67945 0.3048)
			(stroke
				(width 0.1)
				(type default)
			)
			(layer "F.Fab")
		)
		(fp_line
			(start -0.67945 -0.305054)
			(end -0.12065 -0.305054)
			(stroke
				(width 0.1)
				(type default)
			)
			(layer "F.Fab")
		)
		(fp_line
			(start -0.12065 -0.305054)
			(end -0.12065 -0.2794)
			(stroke
				(width 0.1)
				(type default)
			)
			(layer "F.Fab")
		)
		(pad "1" smd circle
			(at -0.40005 0 270)
			(size 0 0)
			(layers "F.Cu" "F.Mask" "F.Paste")
			(net "PVDDCR_CPU0_P0_VCCS")
		)
		(pad "2" smd circle
			(at 0.40005 0 270)
			(size 0 0)
			(layers "F.Cu" "F.Mask" "F.Paste")
			(net "GND")
		)
	)
	(footprint ""
		(layer "F.Cu")
		(at 331.494892 -385.23926 180)
		(property "Reference" "C962"
			(at 0 0 180)
			(layer "F.SilkS")
			(hide yes)
			(effects
				(font
					(size 1.27 1.27)
				)
			)
		)
		(property "Value" ""
			(at 0 0 180)
			(layer "F.Fab")
			(effects
				(font
					(size 1.27 1.27)
				)
			)
		)
		(duplicate_pad_numbers_are_jumpers no)
		(fp_line
			(start 0.299974 0.150114)
			(end -0.299974 0.150114)
			(stroke
				(width 0.1)
				(type default)
			)
			(layer "F.Fab")
		)
		(fp_line
			(start 0.299974 -0.150114)
			(end 0.299974 0.150114)
			(stroke
				(width 0.1)
				(type default)
			)
			(layer "F.Fab")
		)
		(fp_line
			(start -0.299974 0.150114)
			(end -0.299974 -0.150114)
			(stroke
				(width 0.1)
				(type default)
			)
			(layer "F.Fab")
		)
		(fp_line
			(start -0.299974 -0.150114)
			(end 0.299974 -0.150114)
			(stroke
				(width 0.1)
				(type default)
			)
			(layer "F.Fab")
		)
		(pad "1" smd rect
			(at -0.2667 0 180)
			(size 0.3048 0.381)
			(layers "F.Cu" "F.Mask" "F.Paste")
			(net "P5E_CPU0_P1_TX_C_DN<1>")
		)
		(pad "2" smd rect
			(at 0.2667 0 180)
			(size 0.3048 0.381)
			(layers "F.Cu" "F.Mask" "F.Paste")
			(net "P5E_CPU0_P1_TX_DN<1>")
		)
	)
	(footprint ""
		(layer "F.Cu")
		(at 315.771022 -33.715706 180)
		(property "Reference" "C2176"
			(at 0 0 180)
			(layer "F.SilkS")
			(hide yes)
			(effects
				(font
					(size 1.27 1.27)
				)
			)
		)
		(property "Value" ""
			(at 0 0 180)
			(layer "F.Fab")
			(effects
				(font
					(size 1.27 1.27)
				)
			)
		)
		(duplicate_pad_numbers_are_jumpers no)
		(fp_line
			(start 0.7874 0.4064)
			(end -0.7874 0.4064)
			(stroke
				(width 0.1524)
				(type default)
			)
			(layer "F.SilkS")
		)
		(fp_line
			(start 0.7874 -0.4064)
			(end 0.7874 0.4064)
			(stroke
				(width 0.1524)
				(type default)
			)
			(layer "F.SilkS")
		)
		(fp_line
			(start -0.7874 0.4064)
			(end -0.7874 -0.4064)
			(stroke
				(width 0.1524)
				(type default)
			)
			(layer "F.SilkS")
		)
		(fp_line
			(start -0.7874 -0.4064)
			(end 0.7874 -0.4064)
			(stroke
				(width 0.1524)
				(type default)
			)
			(layer "F.SilkS")
		)
		(fp_line
			(start 0.67945 0.3048)
			(end 0.120396 0.3048)
			(stroke
				(width 0.1)
				(type default)
			)
			(layer "F.Fab")
		)
		(fp_line
			(start 0.67945 -0.3048)
			(end 0.67945 0.3048)
			(stroke
				(width 0.1)
				(type default)
			)
			(layer "F.Fab")
		)
		(fp_line
			(start 0.12065 -0.2794)
			(end 0.12065 -0.3048)
			(stroke
				(width 0.1)
				(type default)
			)
			(layer "F.Fab")
		)
		(fp_line
			(start 0.12065 -0.3048)
			(end 0.67945 -0.3048)
			(stroke
				(width 0.1)
				(type default)
			)
			(layer "F.Fab")
		)
		(fp_line
			(start 0.120396 0.3048)
			(end 0.120396 0.2794)
			(stroke
				(width 0.1)
				(type default)
			)
			(layer "F.Fab")
		)
		(fp_line
			(start 0.120396 0.2794)
			(end -0.12065 0.2794)
			(stroke
				(width 0.1)
				(type default)
			)
			(layer "F.Fab")
		)
		(fp_line
			(start -0.12065 0.3048)
			(end -0.67945 0.3048)
			(stroke
				(width 0.1)
				(type default)
			)
			(layer "F.Fab")
		)
		(fp_line
			(start -0.12065 0.2794)
			(end -0.12065 0.3048)
			(stroke
				(width 0.1)
				(type default)
			)
			(layer "F.Fab")
		)
		(fp_line
			(start -0.12065 -0.2794)
			(end 0.12065 -0.2794)
			(stroke
				(width 0.1)
				(type default)
			)
			(layer "F.Fab")
		)
		(fp_line
			(start -0.12065 -0.305054)
			(end -0.12065 -0.2794)
			(stroke
				(width 0.1)
				(type default)
			)
			(layer "F.Fab")
		)
		(fp_line
			(start -0.67945 0.3048)
			(end -0.67945 -0.305054)
			(stroke
				(width 0.1)
				(type default)
			)
			(layer "F.Fab")
		)
		(fp_line
			(start -0.67945 -0.305054)
			(end -0.12065 -0.305054)
			(stroke
				(width 0.1)
				(type default)
			)
			(layer "F.Fab")
		)
		(pad "1" smd circle
			(at -0.40005 0 180)
			(size 0 0)
			(layers "F.Cu" "F.Mask" "F.Paste")
			(net "P12V_OCP_SFF_ISENSE_MAM")
		)
		(pad "2" smd circle
			(at 0.40005 0 180)
			(size 0 0)
			(layers "F.Cu" "F.Mask" "F.Paste")
			(net "GND")
		)
	)
	(footprint ""
		(layer "F.Cu")
		(at 403.904958 -324.862952 180)
		(property "Reference" "R743"
			(at 0 0 180)
			(layer "F.SilkS")
			(hide yes)
			(effects
				(font
					(size 1.27 1.27)
				)
			)
		)
		(property "Value" ""
			(at 0 0 180)
			(layer "F.Fab")
			(effects
				(font
					(size 1.27 1.27)
				)
			)
		)
		(duplicate_pad_numbers_are_jumpers no)
		(fp_line
			(start 0.7874 0.4064)
			(end -0.7874 0.4064)
			(stroke
				(width 0.1524)
				(type default)
			)
			(layer "F.SilkS")
		)
		(fp_line
			(start 0.7874 -0.4064)
			(end 0.7874 0.4064)
			(stroke
				(width 0.1524)
				(type default)
			)
			(layer "F.SilkS")
		)
		(fp_line
			(start -0.7874 0.4064)
			(end -0.7874 -0.4064)
			(stroke
				(width 0.1524)
				(type default)
			)
			(layer "F.SilkS")
		)
		(fp_line
			(start -0.7874 -0.4064)
			(end 0.7874 -0.4064)
			(stroke
				(width 0.1524)
				(type default)
			)
			(layer "F.SilkS")
		)
		(fp_line
			(start 0.67945 0.3048)
			(end 0.120396 0.3048)
			(stroke
				(width 0.1)
				(type default)
			)
			(layer "F.Fab")
		)
		(fp_line
			(start 0.67945 -0.3048)
			(end 0.67945 0.3048)
			(stroke
				(width 0.1)
				(type default)
			)
			(layer "F.Fab")
		)
		(fp_line
			(start 0.12065 -0.2794)
			(end 0.12065 -0.3048)
			(stroke
				(width 0.1)
				(type default)
			)
			(layer "F.Fab")
		)
		(fp_line
			(start 0.12065 -0.3048)
			(end 0.67945 -0.3048)
			(stroke
				(width 0.1)
				(type default)
			)
			(layer "F.Fab")
		)
		(fp_line
			(start 0.120396 0.3048)
			(end 0.120396 0.2794)
			(stroke
				(width 0.1)
				(type default)
			)
			(layer "F.Fab")
		)
		(fp_line
			(start 0.120396 0.2794)
			(end -0.12065 0.2794)
			(stroke
				(width 0.1)
				(type default)
			)
			(layer "F.Fab")
		)
		(fp_line
			(start -0.12065 0.3048)
			(end -0.67945 0.3048)
			(stroke
				(width 0.1)
				(type default)
			)
			(layer "F.Fab")
		)
		(fp_line
			(start -0.12065 0.2794)
			(end -0.12065 0.3048)
			(stroke
				(width 0.1)
				(type default)
			)
			(layer "F.Fab")
		)
		(fp_line
			(start -0.12065 -0.2794)
			(end 0.12065 -0.2794)
			(stroke
				(width 0.1)
				(type default)
			)
			(layer "F.Fab")
		)
		(fp_line
			(start -0.12065 -0.305054)
			(end -0.12065 -0.2794)
			(stroke
				(width 0.1)
				(type default)
			)
			(layer "F.Fab")
		)
		(fp_line
			(start -0.67945 0.3048)
			(end -0.67945 -0.305054)
			(stroke
				(width 0.1)
				(type default)
			)
			(layer "F.Fab")
		)
		(fp_line
			(start -0.67945 -0.305054)
			(end -0.12065 -0.305054)
			(stroke
				(width 0.1)
				(type default)
			)
			(layer "F.Fab")
		)
		(pad "1" smd circle
			(at -0.40005 0 180)
			(size 0 0)
			(layers "F.Cu" "F.Mask" "F.Paste")
			(net "PVDD18_S5_P0")
		)
		(pad "2" smd circle
			(at 0.40005 0 180)
			(size 0 0)
			(layers "F.Cu" "F.Mask" "F.Paste")
			(net "SPI_CPU0_CLK")
		)
	)
	(footprint ""
		(layer "F.Cu")
		(at 257.242056 -116.87937 180)
		(property "Reference" "R3717"
			(at 0 0 180)
			(layer "F.SilkS")
			(hide yes)
			(effects
				(font
					(size 1.27 1.27)
				)
			)
		)
		(property "Value" ""
			(at 0 0 180)
			(layer "F.Fab")
			(effects
				(font
					(size 1.27 1.27)
				)
			)
		)
		(duplicate_pad_numbers_are_jumpers no)
		(fp_line
			(start 0.7874 0.4064)
			(end -0.7874 0.4064)
			(stroke
				(width 0.1524)
				(type default)
			)
			(layer "F.SilkS")
		)
		(fp_line
			(start 0.7874 -0.4064)
			(end 0.7874 0.4064)
			(stroke
				(width 0.1524)
				(type default)
			)
			(layer "F.SilkS")
		)
		(fp_line
			(start -0.7874 0.4064)
			(end -0.7874 -0.4064)
			(stroke
				(width 0.1524)
				(type default)
			)
			(layer "F.SilkS")
		)
		(fp_line
			(start -0.7874 -0.4064)
			(end 0.7874 -0.4064)
			(stroke
				(width 0.1524)
				(type default)
			)
			(layer "F.SilkS")
		)
		(fp_line
			(start 0.67945 0.3048)
			(end 0.120396 0.3048)
			(stroke
				(width 0.1)
				(type default)
			)
			(layer "F.Fab")
		)
		(fp_line
			(start 0.67945 -0.3048)
			(end 0.67945 0.3048)
			(stroke
				(width 0.1)
				(type default)
			)
			(layer "F.Fab")
		)
		(fp_line
			(start 0.12065 -0.2794)
			(end 0.12065 -0.3048)
			(stroke
				(width 0.1)
				(type default)
			)
			(layer "F.Fab")
		)
		(fp_line
			(start 0.12065 -0.3048)
			(end 0.67945 -0.3048)
			(stroke
				(width 0.1)
				(type default)
			)
			(layer "F.Fab")
		)
		(fp_line
			(start 0.120396 0.3048)
			(end 0.120396 0.2794)
			(stroke
				(width 0.1)
				(type default)
			)
			(layer "F.Fab")
		)
		(fp_line
			(start 0.120396 0.2794)
			(end -0.12065 0.2794)
			(stroke
				(width 0.1)
				(type default)
			)
			(layer "F.Fab")
		)
		(fp_line
			(start -0.12065 0.3048)
			(end -0.67945 0.3048)
			(stroke
				(width 0.1)
				(type default)
			)
			(layer "F.Fab")
		)
		(fp_line
			(start -0.12065 0.2794)
			(end -0.12065 0.3048)
			(stroke
				(width 0.1)
				(type default)
			)
			(layer "F.Fab")
		)
		(fp_line
			(start -0.12065 -0.2794)
			(end 0.12065 -0.2794)
			(stroke
				(width 0.1)
				(type default)
			)
			(layer "F.Fab")
		)
		(fp_line
			(start -0.12065 -0.305054)
			(end -0.12065 -0.2794)
			(stroke
				(width 0.1)
				(type default)
			)
			(layer "F.Fab")
		)
		(fp_line
			(start -0.67945 0.3048)
			(end -0.67945 -0.305054)
			(stroke
				(width 0.1)
				(type default)
			)
			(layer "F.Fab")
		)
		(fp_line
			(start -0.67945 -0.305054)
			(end -0.12065 -0.305054)
			(stroke
				(width 0.1)
				(type default)
			)
			(layer "F.Fab")
		)
		(pad "1" smd circle
			(at -0.40005 0 180)
			(size 0 0)
			(layers "F.Cu" "F.Mask" "F.Paste")
			(net "SMB_LM75_1_3V3AUX_SCL_R")
		)
		(pad "2" smd circle
			(at 0.40005 0 180)
			(size 0 0)
			(layers "F.Cu" "F.Mask" "F.Paste")
			(net "SMB_LM75_1_3V3AUX_SCL")
		)
	)
	(footprint ""
		(layer "F.Cu")
		(at 264.478516 -135.654796 180)
		(property "Reference" "R659"
			(at 0 0 180)
			(layer "F.SilkS")
			(hide yes)
			(effects
				(font
					(size 1.27 1.27)
				)
			)
		)
		(property "Value" ""
			(at 0 0 180)
			(layer "F.Fab")
			(effects
				(font
					(size 1.27 1.27)
				)
			)
		)
		(duplicate_pad_numbers_are_jumpers no)
		(fp_line
			(start 0.7874 0.4064)
			(end -0.7874 0.4064)
			(stroke
				(width 0.1524)
				(type default)
			)
			(layer "F.SilkS")
		)
		(fp_line
			(start 0.7874 -0.4064)
			(end 0.7874 0.4064)
			(stroke
				(width 0.1524)
				(type default)
			)
			(layer "F.SilkS")
		)
		(fp_line
			(start -0.7874 0.4064)
			(end -0.7874 -0.4064)
			(stroke
				(width 0.1524)
				(type default)
			)
			(layer "F.SilkS")
		)
		(fp_line
			(start -0.7874 -0.4064)
			(end 0.7874 -0.4064)
			(stroke
				(width 0.1524)
				(type default)
			)
			(layer "F.SilkS")
		)
		(fp_line
			(start 0.67945 0.3048)
			(end 0.120396 0.3048)
			(stroke
				(width 0.1)
				(type default)
			)
			(layer "F.Fab")
		)
		(fp_line
			(start 0.67945 -0.3048)
			(end 0.67945 0.3048)
			(stroke
				(width 0.1)
				(type default)
			)
			(layer "F.Fab")
		)
		(fp_line
			(start 0.12065 -0.2794)
			(end 0.12065 -0.3048)
			(stroke
				(width 0.1)
				(type default)
			)
			(layer "F.Fab")
		)
		(fp_line
			(start 0.12065 -0.3048)
			(end 0.67945 -0.3048)
			(stroke
				(width 0.1)
				(type default)
			)
			(layer "F.Fab")
		)
		(fp_line
			(start 0.120396 0.3048)
			(end 0.120396 0.2794)
			(stroke
				(width 0.1)
				(type default)
			)
			(layer "F.Fab")
		)
		(fp_line
			(start 0.120396 0.2794)
			(end -0.12065 0.2794)
			(stroke
				(width 0.1)
				(type default)
			)
			(layer "F.Fab")
		)
		(fp_line
			(start -0.12065 0.3048)
			(end -0.67945 0.3048)
			(stroke
				(width 0.1)
				(type default)
			)
			(layer "F.Fab")
		)
		(fp_line
			(start -0.12065 0.2794)
			(end -0.12065 0.3048)
			(stroke
				(width 0.1)
				(type default)
			)
			(layer "F.Fab")
		)
		(fp_line
			(start -0.12065 -0.2794)
			(end 0.12065 -0.2794)
			(stroke
				(width 0.1)
				(type default)
			)
			(layer "F.Fab")
		)
		(fp_line
			(start -0.12065 -0.305054)
			(end -0.12065 -0.2794)
			(stroke
				(width 0.1)
				(type default)
			)
			(layer "F.Fab")
		)
		(fp_line
			(start -0.67945 0.3048)
			(end -0.67945 -0.305054)
			(stroke
				(width 0.1)
				(type default)
			)
			(layer "F.Fab")
		)
		(fp_line
			(start -0.67945 -0.305054)
			(end -0.12065 -0.305054)
			(stroke
				(width 0.1)
				(type default)
			)
			(layer "F.Fab")
		)
		(pad "1" smd circle
			(at -0.40005 0 180)
			(size 0 0)
			(layers "F.Cu" "F.Mask" "F.Paste")
			(net "PVDD18_S5_P0")
		)
		(pad "2" smd circle
			(at 0.40005 0 180)
			(size 0 0)
			(layers "F.Cu" "F.Mask" "F.Paste")
			(net "SPI_CPU0_TPM_CS_N")
		)
	)
	(footprint ""
		(layer "F.Cu")
		(at 183.420766 -168.317418 -90)
		(property "Reference" "R5013"
			(at 0 0 270)
			(layer "F.SilkS")
			(hide yes)
			(effects
				(font
					(size 1.27 1.27)
				)
			)
		)
		(property "Value" ""
			(at 0 0 270)
			(layer "F.Fab")
			(effects
				(font
					(size 1.27 1.27)
				)
			)
		)
		(duplicate_pad_numbers_are_jumpers no)
		(fp_line
			(start -0.7874 0.4064)
			(end -0.7874 -0.4064)
			(stroke
				(width 0.1524)
				(type default)
			)
			(layer "F.SilkS")
		)
		(fp_line
			(start 0.7874 0.4064)
			(end -0.7874 0.4064)
			(stroke
				(width 0.1524)
				(type default)
			)
			(layer "F.SilkS")
		)
		(fp_line
			(start -0.7874 -0.4064)
			(end 0.7874 -0.4064)
			(stroke
				(width 0.1524)
				(type default)
			)
			(layer "F.SilkS")
		)
		(fp_line
			(start 0.7874 -0.4064)
			(end 0.7874 0.4064)
			(stroke
				(width 0.1524)
				(type default)
			)
			(layer "F.SilkS")
		)
		(fp_line
			(start -0.67945 0.3048)
			(end -0.67945 -0.305054)
			(stroke
				(width 0.1)
				(type default)
			)
			(layer "F.Fab")
		)
		(fp_line
			(start -0.12065 0.3048)
			(end -0.67945 0.3048)
			(stroke
				(width 0.1)
				(type default)
			)
			(layer "F.Fab")
		)
		(fp_line
			(start 0.120396 0.3048)
			(end 0.120396 0.2794)
			(stroke
				(width 0.1)
				(type default)
			)
			(layer "F.Fab")
		)
		(fp_line
			(start 0.67945 0.3048)
			(end 0.120396 0.3048)
			(stroke
				(width 0.1)
				(type default)
			)
			(layer "F.Fab")
		)
		(fp_line
			(start -0.12065 0.2794)
			(end -0.12065 0.3048)
			(stroke
				(width 0.1)
				(type default)
			)
			(layer "F.Fab")
		)
		(fp_line
			(start 0.120396 0.2794)
			(end -0.12065 0.2794)
			(stroke
				(width 0.1)
				(type default)
			)
			(layer "F.Fab")
		)
		(fp_line
			(start -0.12065 -0.2794)
			(end 0.12065 -0.2794)
			(stroke
				(width 0.1)
				(type default)
			)
			(layer "F.Fab")
		)
		(fp_line
			(start 0.12065 -0.2794)
			(end 0.12065 -0.3048)
			(stroke
				(width 0.1)
				(type default)
			)
			(layer "F.Fab")
		)
		(fp_line
			(start 0.12065 -0.3048)
			(end 0.67945 -0.3048)
			(stroke
				(width 0.1)
				(type default)
			)
			(layer "F.Fab")
		)
		(fp_line
			(start 0.67945 -0.3048)
			(end 0.67945 0.3048)
			(stroke
				(width 0.1)
				(type default)
			)
			(layer "F.Fab")
		)
		(fp_line
			(start -0.67945 -0.305054)
			(end -0.12065 -0.305054)
			(stroke
				(width 0.1)
				(type default)
			)
			(layer "F.Fab")
		)
		(fp_line
			(start -0.12065 -0.305054)
			(end -0.12065 -0.2794)
			(stroke
				(width 0.1)
				(type default)
			)
			(layer "F.Fab")
		)
		(pad "1" smd circle
			(at -0.40005 0 270)
			(size 0 0)
			(layers "F.Cu" "F.Mask" "F.Paste")
			(net "PVDD11_S3_P1")
		)
		(pad "2" smd circle
			(at 0.40005 0 270)
			(size 0 0)
			(layers "F.Cu" "F.Mask" "F.Paste")
			(net "I3C_SPD_DDRGL_CPU1_LVC1_SDA")
		)
	)
)
